(kicad_pcb
	(version 20260206)
	(generator "pcbnew")
	(generator_version "10.0")
	(general
		(thickness 1.6)
		(legacy_teardrops no)
	)
	(paper "A4")
	(title_block
		(title "netronome-mezz — pcbd0082-001_rev01_jul9_a.brd")
		(comment 1 "Open CloudServer (Microsoft) / footprints 476-485 of 714")
	)
	(layers
		(0 "F.Cu" signal "TOP")
		(4 "In1.Cu" signal "02_GND")
		(6 "In2.Cu" signal "03_SIG")
		(8 "In3.Cu" signal "04_SIG")
		(10 "In4.Cu" signal "05_GND")
		(12 "In5.Cu" signal "06_PWR1")
		(14 "In6.Cu" signal "07_SIG")
		(16 "In7.Cu" signal "08_SIG")
		(18 "In8.Cu" signal "09_GND")
		(2 "B.Cu" signal "BOTTOM")
		(9 "F.Adhes" user "F.Adhesive")
		(11 "B.Adhes" user "B.Adhesive")
		(13 "F.Paste" user "Package Geometry/Pastemask Top")
		(15 "B.Paste" user "Package Geometry/Pastemask Bottom")
		(5 "F.SilkS" user "Ref Des/Silkscreen Top")
		(7 "B.SilkS" user "Ref Des/Silkscreen Bottom")
		(1 "F.Mask" user "Board Geometry/Soldermask Top")
		(3 "B.Mask" user "Board Geometry/Soldermask Bottom")
		(17 "Dwgs.User" user "User.Drawings")
		(19 "Cmts.User" user "User.Comments")
		(21 "Eco1.User" user "User.Eco1")
		(23 "Eco2.User" user "User.Eco2")
		(25 "Edge.Cuts" user "Board Geometry/Outline")
		(27 "Margin" user)
		(31 "F.CrtYd" user "Package Geometry/Place Bound Top")
		(29 "B.CrtYd" user "Package Geometry/Place Bound Bottom")
		(35 "F.Fab" user "Ref Des/Assembly Top")
		(33 "B.Fab" user "Ref Des/Assembly Bottom")
		(45 "User.4" user "COMPVAL_TYPE_BOTTOM")
	)
	(footprint ""
		(layer "B.Cu")
		(at 62.221999 0.762 180)
		(property "Reference" "C153"
			(at 0.145212 0.8763 270)
			(unlocked yes)
			(layer "B.SilkS")
			(effects
				(font
					(size 0.7874 0.5842)
					(thickness 0.127)
				)
				(justify left mirror)
			)
		)
		(property "Value" "0.22UF"
			(at 0.091846 0.2921 90)
			(unlocked yes)
			(layer "B.Fab")
			(hide yes)
			(effects
				(font
					(size 0.7874 0.5842)
					(thickness 0.2032)
				)
				(justify left mirror)
			)
		)
		(property "Device Type" "CAPC0062"
			(at 0.091846 0.2921 90)
			(unlocked yes)
			(layer "B.Fab")
			(hide yes)
			(effects
				(font
					(size 0.7874 0.5842)
					(thickness 0.2032)
				)
				(justify left mirror)
			)
		)
		(duplicate_pad_numbers_are_jumpers no)
		(fp_poly
			(pts
				(xy -0.635 1.0668) (xy -0.635 -1.0668) (xy 0.635 -1.0668) (xy 0.635 1.0668)
			)
			(stroke
				(width 0)
				(type default)
			)
			(fill no)
			(layer "B.CrtYd")
		)
		(fp_line
			(start 0.254 0.508)
			(end 0.254 -0.508)
			(stroke
				(width 0.0254)
				(type default)
			)
			(layer "B.Fab")
		)
		(fp_line
			(start 0.254 -0.508)
			(end -0.254 -0.508)
			(stroke
				(width 0.0254)
				(type default)
			)
			(layer "B.Fab")
		)
		(fp_line
			(start -0.254 0.508)
			(end 0.254 0.508)
			(stroke
				(width 0.0254)
				(type default)
			)
			(layer "B.Fab")
		)
		(fp_line
			(start -0.254 -0.508)
			(end -0.254 0.508)
			(stroke
				(width 0.0254)
				(type default)
			)
			(layer "B.Fab")
		)
		(pad "1" smd rect
			(at 0 -0.4191)
			(size 0.508 0.5334)
			(layers "B.Cu" "B.Mask" "B.Paste")
			(net "_NFP_PCIE0_PER0_P")
		)
		(pad "2" smd rect
			(at 0 0.4191)
			(size 0.508 0.5334)
			(layers "B.Cu" "B.Mask" "B.Paste")
			(net "NFP_PCIE0_PER0_P")
		)
		(zone
			(layer "B.Cu")
			(hatch none 0.5)
			(connect_pads
				(clearance 0)
			)
			(min_thickness 0.25)
			(keepout
				(tracks not_allowed)
				(vias allowed)
				(pads allowed)
				(copperpour not_allowed)
				(footprints allowed)
			)
			(placement
				(enabled no)
				(sheetname "")
			)
			(fill
				(thermal_gap 0.5)
				(thermal_bridge_width 0.5)
				(island_removal_mode 0)
			)
			(polygon
				(pts
					(xy 62.247399 0.7874) (xy 62.247399 0.7366) (xy 62.196599 0.7366) (xy 62.196599 0.7874)
				)
			)
		)
	)
	(footprint ""
		(layer "B.Cu")
		(at 37.592 19.304 -90)
		(property "Reference" "R202"
			(at 0 0 90)
			(layer "B.SilkS")
			(hide yes)
			(effects
				(font
					(size 1.27 1.27)
				)
				(justify mirror)
			)
		)
		(property "Value" "39.0"
			(at 0.148158 1.3462 180)
			(unlocked yes)
			(layer "B.Fab")
			(hide yes)
			(effects
				(font
					(size 1.27 0.9652)
					(thickness 0.000001)
				)
				(justify left mirror)
			)
		)
		(property "Device Type" "REST0108"
			(at 0.148158 1.3462 180)
			(unlocked yes)
			(layer "B.Fab")
			(hide yes)
			(effects
				(font
					(size 1.27 0.9652)
					(thickness 0.000001)
				)
				(justify left mirror)
			)
		)
		(duplicate_pad_numbers_are_jumpers no)
		(fp_poly
			(pts
				(xy -0.635 1.0668) (xy -0.635 -1.0668) (xy 0.635 -1.0668) (xy 0.635 1.0668)
			)
			(stroke
				(width 0)
				(type default)
			)
			(fill no)
			(layer "B.CrtYd")
		)
		(fp_line
			(start -0.254 0.508)
			(end 0.254 0.508)
			(stroke
				(width 0.0254)
				(type default)
			)
			(layer "B.Fab")
		)
		(fp_line
			(start 0.254 0.508)
			(end 0.254 -0.508)
			(stroke
				(width 0.0254)
				(type default)
			)
			(layer "B.Fab")
		)
		(fp_line
			(start -0.254 -0.508)
			(end -0.254 0.508)
			(stroke
				(width 0.0254)
				(type default)
			)
			(layer "B.Fab")
		)
		(fp_line
			(start 0.254 -0.508)
			(end -0.254 -0.508)
			(stroke
				(width 0.0254)
				(type default)
			)
			(layer "B.Fab")
		)
		(pad "1" smd rect
			(at 0 -0.4191 90)
			(size 0.508 0.5334)
			(layers "B.Cu" "B.Mask" "B.Paste")
			(net "_NFP_CFG_SPI_FLASH_MOSI")
		)
		(pad "2" smd rect
			(at 0 0.4191 90)
			(size 0.508 0.5334)
			(layers "B.Cu" "B.Mask" "B.Paste")
			(net "NFP_CFG_SPI_FLASH_MOSI")
		)
		(zone
			(layer "B.Cu")
			(hatch none 0.5)
			(connect_pads
				(clearance 0)
			)
			(min_thickness 0.25)
			(keepout
				(tracks not_allowed)
				(vias allowed)
				(pads allowed)
				(copperpour not_allowed)
				(footprints allowed)
			)
			(placement
				(enabled no)
				(sheetname "")
			)
			(fill
				(thermal_gap 0.5)
				(thermal_bridge_width 0.5)
				(island_removal_mode 0)
			)
			(polygon
				(pts
					(xy 37.6174 19.2786) (xy 37.5666 19.2786) (xy 37.5666 19.3294) (xy 37.6174 19.3294)
				)
			)
		)
	)
	(footprint ""
		(layer "B.Cu")
		(at 45.737018 1.042035 180)
		(property "Reference" "L15"
			(at -0.998982 1.142365 0)
			(unlocked yes)
			(layer "B.SilkS")
			(effects
				(font
					(size 0.7874 0.5842)
					(thickness 0.127)
				)
				(justify left mirror)
			)
		)
		(property "Value" ""
			(at 0 0 0)
			(layer "B.Fab")
			(effects
				(font
					(size 1.27 1.27)
				)
				(justify mirror)
			)
		)
		(duplicate_pad_numbers_are_jumpers no)
		(fp_rect
			(start -1.7907 0.889)
			(end 1.7907 -0.889)
			(stroke
				(width 0)
				(type default)
			)
			(fill no)
			(layer "B.CrtYd")
		)
		(fp_line
			(start 1.778 0.762)
			(end 1.778 -0.762)
			(stroke
				(width 0.0254)
				(type default)
			)
			(layer "B.Fab")
		)
		(fp_line
			(start 1.778 -0.762)
			(end -1.778 -0.762)
			(stroke
				(width 0.0254)
				(type default)
			)
			(layer "B.Fab")
		)
		(fp_line
			(start -1.778 0.762)
			(end 1.778 0.762)
			(stroke
				(width 0.0254)
				(type default)
			)
			(layer "B.Fab")
		)
		(fp_line
			(start -1.778 -0.762)
			(end -1.778 0.762)
			(stroke
				(width 0.0254)
				(type default)
			)
			(layer "B.Fab")
		)
		(pad "1" smd rect
			(at 0.7493 0 270)
			(size 0.7874 0.8128)
			(layers "B.Cu" "B.Mask" "B.Paste")
			(net "VDD_1.8V")
		)
		(pad "2" smd rect
			(at -0.7493 0 270)
			(size 0.7874 0.8128)
			(layers "B.Cu" "B.Mask" "B.Paste")
			(net "VDDAH_SERDES")
		)
		(zone
			(layer "B.Cu")
			(hatch none 0.5)
			(connect_pads
				(clearance 0)
			)
			(min_thickness 0.25)
			(keepout
				(tracks not_allowed)
				(vias allowed)
				(pads allowed)
				(copperpour not_allowed)
				(footprints allowed)
			)
			(placement
				(enabled no)
				(sheetname "")
			)
			(fill
				(thermal_gap 0.5)
				(thermal_bridge_width 0.5)
				(island_removal_mode 0)
			)
			(polygon
				(pts
					(xy 45.457618 1.448435) (xy 45.457618 0.635635) (xy 46.016418 0.635635) (xy 46.016418 1.448435)
				)
			)
		)
	)
	(footprint ""
		(layer "B.Cu")
		(at 58.236993 26.541984)
		(property "Reference" "C8"
			(at 0.029337 -2.030984 270)
			(unlocked yes)
			(layer "B.SilkS")
			(effects
				(font
					(size 0.7874 0.5842)
					(thickness 0.127)
				)
				(justify mirror)
			)
		)
		(property "Value" ""
			(at 0 0 0)
			(layer "B.Fab")
			(effects
				(font
					(size 1.27 1.27)
				)
				(justify mirror)
			)
		)
		(duplicate_pad_numbers_are_jumpers no)
		(fp_circle
			(center 0 0)
			(end 0.104648 0)
			(stroke
				(width 0.1016)
				(type default)
			)
			(fill no)
			(layer "B.SilkS")
		)
		(fp_poly
			(pts
				(xy 0.381 -0.889) (xy 0.381 0.889) (xy -0.381 0.889) (xy -0.381 -0.889)
			)
			(stroke
				(width 0)
				(type default)
			)
			(fill no)
			(layer "B.CrtYd")
		)
		(fp_line
			(start -0.508 -1.016)
			(end -0.508 1.016)
			(stroke
				(width 0.0254)
				(type default)
			)
			(layer "B.Fab")
		)
		(fp_line
			(start -0.508 1.016)
			(end 0.508 1.016)
			(stroke
				(width 0.0254)
				(type default)
			)
			(layer "B.Fab")
		)
		(fp_line
			(start 0.254 -1.016)
			(end -0.508 -1.016)
			(stroke
				(width 0.0254)
				(type default)
			)
			(layer "B.Fab")
		)
		(fp_line
			(start 0.508 -1.016)
			(end 0.254 -1.016)
			(stroke
				(width 0.0254)
				(type default)
			)
			(layer "B.Fab")
		)
		(fp_line
			(start 0.508 1.016)
			(end 0.508 -1.016)
			(stroke
				(width 0.0254)
				(type default)
			)
			(layer "B.Fab")
		)
		(pad "1" smd custom
			(at 0 -0.500126 180)
			(size 0.127 0.127)
			(layers "B.Cu" "B.Mask" "B.Paste")
			(net "VDD_CORE")
			(options
				(clearance outline)
				(anchor circle)
			)
			(primitives
				(gr_poly
					(pts
						(xy -0.1778 0.254) (xy 0.1778 0.254) (xy 0.254 0.1778) (xy 0.254 -0.1778) (xy 0.1778 -0.254) (xy -0.1778 -0.254)
						(xy -0.254 -0.1778) (xy -0.254 0.1778)
					)
					(width 0)
					(fill yes)
				)
			)
		)
		(pad "2" smd custom
			(at 0 0.500126 180)
			(size 0.127 0.127)
			(layers "B.Cu" "B.Mask" "B.Paste")
			(net "GND")
			(options
				(clearance outline)
				(anchor circle)
			)
			(primitives
				(gr_poly
					(pts
						(xy -0.1778 0.254) (xy 0.1778 0.254) (xy 0.254 0.1778) (xy 0.254 -0.1778) (xy 0.1778 -0.254) (xy -0.1778 -0.254)
						(xy -0.254 -0.1778) (xy -0.254 0.1778)
					)
					(width 0)
					(fill yes)
				)
			)
		)
	)
	(footprint ""
		(layer "B.Cu")
		(at 83.450989 1.899006)
		(property "Reference" "V1_A-A07"
			(at 0 0 0)
			(layer "B.SilkS")
			(hide yes)
			(effects
				(font
					(size 1.27 1.27)
				)
				(justify mirror)
			)
		)
		(property "Value" ""
			(at 0 0 0)
			(layer "B.Fab")
			(effects
				(font
					(size 1.27 1.27)
				)
				(justify mirror)
			)
		)
		(duplicate_pad_numbers_are_jumpers no)
		(pad "1" thru_hole circle
			(at 0 0 180)
			(size 0.4572 0.4572)
			(drill 0.20574)
			(layers "*.Cu" "*.Mask")
			(remove_unused_layers no)
			(net "DDR0_32A_A7")
			(clearance 0.1143)
			(thermal_gap 0.1143)
		)
	)
	(footprint ""
		(layer "B.Cu")
		(at 61.214 0.762 180)
		(property "Reference" "C156"
			(at 0.145212 0.8763 270)
			(unlocked yes)
			(layer "B.SilkS")
			(effects
				(font
					(size 0.7874 0.5842)
					(thickness 0.127)
				)
				(justify left mirror)
			)
		)
		(property "Value" "0.22UF"
			(at 0.091846 0.2921 90)
			(unlocked yes)
			(layer "B.Fab")
			(hide yes)
			(effects
				(font
					(size 0.7874 0.5842)
					(thickness 0.2032)
				)
				(justify left mirror)
			)
		)
		(property "Device Type" "CAPC0062"
			(at 0.091846 0.2921 90)
			(unlocked yes)
			(layer "B.Fab")
			(hide yes)
			(effects
				(font
					(size 0.7874 0.5842)
					(thickness 0.2032)
				)
				(justify left mirror)
			)
		)
		(duplicate_pad_numbers_are_jumpers no)
		(fp_poly
			(pts
				(xy -0.635 1.0668) (xy -0.635 -1.0668) (xy 0.635 -1.0668) (xy 0.635 1.0668)
			)
			(stroke
				(width 0)
				(type default)
			)
			(fill no)
			(layer "B.CrtYd")
		)
		(fp_line
			(start 0.254 0.508)
			(end 0.254 -0.508)
			(stroke
				(width 0.0254)
				(type default)
			)
			(layer "B.Fab")
		)
		(fp_line
			(start 0.254 -0.508)
			(end -0.254 -0.508)
			(stroke
				(width 0.0254)
				(type default)
			)
			(layer "B.Fab")
		)
		(fp_line
			(start -0.254 0.508)
			(end 0.254 0.508)
			(stroke
				(width 0.0254)
				(type default)
			)
			(layer "B.Fab")
		)
		(fp_line
			(start -0.254 -0.508)
			(end -0.254 0.508)
			(stroke
				(width 0.0254)
				(type default)
			)
			(layer "B.Fab")
		)
		(pad "1" smd rect
			(at 0 -0.4191)
			(size 0.508 0.5334)
			(layers "B.Cu" "B.Mask" "B.Paste")
			(net "_NFP_PCIE0_PER1_N")
		)
		(pad "2" smd rect
			(at 0 0.4191)
			(size 0.508 0.5334)
			(layers "B.Cu" "B.Mask" "B.Paste")
			(net "NFP_PCIE0_PER1_N")
		)
		(zone
			(layer "B.Cu")
			(hatch none 0.5)
			(connect_pads
				(clearance 0)
			)
			(min_thickness 0.25)
			(keepout
				(tracks not_allowed)
				(vias allowed)
				(pads allowed)
				(copperpour not_allowed)
				(footprints allowed)
			)
			(placement
				(enabled no)
				(sheetname "")
			)
			(fill
				(thermal_gap 0.5)
				(thermal_bridge_width 0.5)
				(island_removal_mode 0)
			)
			(polygon
				(pts
					(xy 61.2394 0.7874) (xy 61.2394 0.7366) (xy 61.1886 0.7366) (xy 61.1886 0.7874)
				)
			)
		)
	)
	(footprint ""
		(layer "B.Cu")
		(at 84.250987 7.498994)
		(property "Reference" "V1_A-A08"
			(at 0 0 0)
			(layer "B.SilkS")
			(hide yes)
			(effects
				(font
					(size 1.27 1.27)
				)
				(justify mirror)
			)
		)
		(property "Value" ""
			(at 0 0 0)
			(layer "B.Fab")
			(effects
				(font
					(size 1.27 1.27)
				)
				(justify mirror)
			)
		)
		(duplicate_pad_numbers_are_jumpers no)
		(pad "1" thru_hole circle
			(at 0 0 180)
			(size 0.4572 0.4572)
			(drill 0.20574)
			(layers "*.Cu" "*.Mask")
			(remove_unused_layers no)
			(net "DDR0_32A_A8")
			(clearance 0.1143)
			(thermal_gap 0.1143)
		)
	)
	(footprint ""
		(layer "B.Cu")
		(at 35.433 32.639)
		(property "Reference" "R81"
			(at 0.48133 3.429 270)
			(unlocked yes)
			(layer "B.SilkS")
			(effects
				(font
					(size 0.7874 0.5842)
					(thickness 0.127)
				)
				(justify left mirror)
			)
		)
		(property "Value" "4.75K"
			(at 0.148158 1.3462 270)
			(unlocked yes)
			(layer "B.Fab")
			(hide yes)
			(effects
				(font
					(size 1.27 0.9652)
					(thickness 0.000001)
				)
				(justify left mirror)
			)
		)
		(property "Device Type" "REST4024"
			(at 0.148158 1.3462 270)
			(unlocked yes)
			(layer "B.Fab")
			(hide yes)
			(effects
				(font
					(size 1.27 0.9652)
					(thickness 0.000001)
				)
				(justify left mirror)
			)
		)
		(duplicate_pad_numbers_are_jumpers no)
		(fp_poly
			(pts
				(xy -0.635 1.0668) (xy -0.635 -1.0668) (xy 0.635 -1.0668) (xy 0.635 1.0668)
			)
			(stroke
				(width 0)
				(type default)
			)
			(fill no)
			(layer "B.CrtYd")
		)
		(fp_line
			(start -0.254 -0.508)
			(end -0.254 0.508)
			(stroke
				(width 0.0254)
				(type default)
			)
			(layer "B.Fab")
		)
		(fp_line
			(start -0.254 0.508)
			(end 0.254 0.508)
			(stroke
				(width 0.0254)
				(type default)
			)
			(layer "B.Fab")
		)
		(fp_line
			(start 0.254 -0.508)
			(end -0.254 -0.508)
			(stroke
				(width 0.0254)
				(type default)
			)
			(layer "B.Fab")
		)
		(fp_line
			(start 0.254 0.508)
			(end 0.254 -0.508)
			(stroke
				(width 0.0254)
				(type default)
			)
			(layer "B.Fab")
		)
		(pad "1" smd rect
			(at 0 -0.4191 180)
			(size 0.508 0.5334)
			(layers "B.Cu" "B.Mask" "B.Paste")
			(net "GND")
		)
		(pad "2" smd rect
			(at 0 0.4191 180)
			(size 0.508 0.5334)
			(layers "B.Cu" "B.Mask" "B.Paste")
			(net "_NFP_CORE_VID7")
		)
		(zone
			(layer "B.Cu")
			(hatch none 0.5)
			(connect_pads
				(clearance 0)
			)
			(min_thickness 0.25)
			(keepout
				(tracks not_allowed)
				(vias allowed)
				(pads allowed)
				(copperpour not_allowed)
				(footprints allowed)
			)
			(placement
				(enabled no)
				(sheetname "")
			)
			(fill
				(thermal_gap 0.5)
				(thermal_bridge_width 0.5)
				(island_removal_mode 0)
			)
			(polygon
				(pts
					(xy 35.4076 32.6136) (xy 35.4076 32.6644) (xy 35.4584 32.6644) (xy 35.4584 32.6136)
				)
			)
		)
	)
	(footprint ""
		(layer "B.Cu")
		(at 38.989 44.831)
		(property "Reference" "TP11"
			(at 2.159 -2.38633 0)
			(unlocked yes)
			(layer "B.SilkS")
			(effects
				(font
					(size 0.7874 0.5842)
					(thickness 0.127)
				)
				(justify left mirror)
			)
		)
		(property "Value" "*"
			(at 0.4826 -0.14732 0)
			(unlocked yes)
			(layer "B.Fab")
			(hide yes)
			(effects
				(font
					(size 1.27 0.9652)
					(thickness 0.000001)
				)
				(justify left mirror)
			)
		)
		(property "Device Type" "TP_SMALL"
			(at 0.4826 -0.14732 0)
			(unlocked yes)
			(layer "B.Fab")
			(hide yes)
			(effects
				(font
					(size 1.27 0.9652)
					(thickness 0.000001)
				)
				(justify left mirror)
			)
		)
		(duplicate_pad_numbers_are_jumpers no)
		(fp_line
			(start -0.8636 -0.8636)
			(end 0.8636 -0.8636)
			(stroke
				(width 0.1524)
				(type default)
			)
			(layer "B.SilkS")
		)
		(fp_line
			(start -0.8636 0.8636)
			(end -0.8636 -0.8636)
			(stroke
				(width 0.1524)
				(type default)
			)
			(layer "B.SilkS")
		)
		(fp_line
			(start 0.8636 -0.8636)
			(end 0.8636 0.8636)
			(stroke
				(width 0.1524)
				(type default)
			)
			(layer "B.SilkS")
		)
		(fp_line
			(start 0.8636 0.8636)
			(end -0.8636 0.8636)
			(stroke
				(width 0.1524)
				(type default)
			)
			(layer "B.SilkS")
		)
		(fp_poly
			(pts
				(xy 0.635 -0.635) (xy 0.635 0.635) (xy -0.635 0.635) (xy -0.635 -0.635)
			)
			(stroke
				(width 0)
				(type default)
			)
			(fill no)
			(layer "B.CrtYd")
		)
		(pad "1" smd rect
			(at 0 0 180)
			(size 1.27 1.27)
			(layers "B.Cu" "B.Mask" "B.Paste")
			(net "DEBUG_CPLD_PGRM_JTAG_TMS")
		)
	)
	(footprint ""
		(layer "B.Cu")
		(at 55.437024 0.762 180)
		(property "Reference" "C146"
			(at 0.145212 0.8763 270)
			(unlocked yes)
			(layer "B.SilkS")
			(effects
				(font
					(size 0.7874 0.5842)
					(thickness 0.127)
				)
				(justify left mirror)
			)
		)
		(property "Value" "0.22UF"
			(at 0.091846 0.2921 90)
			(unlocked yes)
			(layer "B.Fab")
			(hide yes)
			(effects
				(font
					(size 0.7874 0.5842)
					(thickness 0.2032)
				)
				(justify left mirror)
			)
		)
		(property "Device Type" "CAPC0062"
			(at 0.091846 0.2921 90)
			(unlocked yes)
			(layer "B.Fab")
			(hide yes)
			(effects
				(font
					(size 0.7874 0.5842)
					(thickness 0.2032)
				)
				(justify left mirror)
			)
		)
		(duplicate_pad_numbers_are_jumpers no)
		(fp_poly
			(pts
				(xy -0.635 1.0668) (xy -0.635 -1.0668) (xy 0.635 -1.0668) (xy 0.635 1.0668)
			)
			(stroke
				(width 0)
				(type default)
			)
			(fill no)
			(layer "B.CrtYd")
		)
		(fp_line
			(start 0.254 0.508)
			(end 0.254 -0.508)
			(stroke
				(width 0.0254)
				(type default)
			)
			(layer "B.Fab")
		)
		(fp_line
			(start 0.254 -0.508)
			(end -0.254 -0.508)
			(stroke
				(width 0.0254)
				(type default)
			)
			(layer "B.Fab")
		)
		(fp_line
			(start -0.254 0.508)
			(end 0.254 0.508)
			(stroke
				(width 0.0254)
				(type default)
			)
			(layer "B.Fab")
		)
		(fp_line
			(start -0.254 -0.508)
			(end -0.254 0.508)
			(stroke
				(width 0.0254)
				(type default)
			)
			(layer "B.Fab")
		)
		(pad "1" smd rect
			(at 0 -0.4191)
			(size 0.508 0.5334)
			(layers "B.Cu" "B.Mask" "B.Paste")
			(net "_NFP_PCIE0_PER4_N")
		)
		(pad "2" smd rect
			(at 0 0.4191)
			(size 0.508 0.5334)
			(layers "B.Cu" "B.Mask" "B.Paste")
			(net "NFP_PCIE0_PER4_N")
		)
		(zone
			(layer "B.Cu")
			(hatch none 0.5)
			(connect_pads
				(clearance 0)
			)
			(min_thickness 0.25)
			(keepout
				(tracks not_allowed)
				(vias allowed)
				(pads allowed)
				(copperpour not_allowed)
				(footprints allowed)
			)
			(placement
				(enabled no)
				(sheetname "")
			)
			(fill
				(thermal_gap 0.5)
				(thermal_bridge_width 0.5)
				(island_removal_mode 0)
			)
			(polygon
				(pts
					(xy 55.462424 0.7874) (xy 55.462424 0.7366) (xy 55.411624 0.7366) (xy 55.411624 0.7874)
				)
			)
		)
	)
)
